# T6G (Grand Teton) — schematic netlist excerpt (pin names and nets, part order shuffled) for the footprints in the layout excerpt that follows; sources: Cadence DE-HDL packaged netlist, KiCad conversion of 04192023_DAF0TMB3IC0_F0TG_MB_C_brd_V02_OCP.brd

R133  Q_RES  0 5% CHIP  pkg 0402LF  page 82 : A = FM_APML_MUX2_SEL ; B = FM_APML_MUX2_SEL_R
PC801  Q_CAPP  390UF 2.5V 20% ALUM  pkg SMLF  page 208 : A = PVDD11_S3_P0 ; B = GND

(kicad_pcb
	(version 20260206)
	(generator "pcbnew")
	(generator_version "10.0")
	(general
		(thickness 1.6)
		(legacy_teardrops no)
	)
	(paper "A4")
	(title_block
		(title "04192023_DAF0TMB3IC0_F0TG_MB_C_brd_V02_OCP.brd")
		(comment 1 "Grand Teton / footprints 1129-1130 of 8354")
	)
	(layers
		(0 "F.Cu" signal "TOP")
		(4 "In1.Cu" signal "GND")
		(6 "In2.Cu" signal "IN1")
		(8 "In3.Cu" signal "GND1")
		(10 "In4.Cu" signal "IN2")
		(12 "In5.Cu" signal "GND2")
		(14 "In6.Cu" signal "IN3")
		(16 "In7.Cu" signal "GND3")
		(18 "In8.Cu" signal "VCC")
		(20 "In9.Cu" signal "VCC1")
		(22 "In10.Cu" signal "GND4")
		(24 "In11.Cu" signal "IN4")
		(26 "In12.Cu" signal "GND5")
		(28 "In13.Cu" signal "IN5")
		(30 "In14.Cu" signal "GND6")
		(32 "In15.Cu" signal "IN6")
		(34 "In16.Cu" signal "GND7")
		(2 "B.Cu" signal "BOTTOM")
		(9 "F.Adhes" user "F.Adhesive")
		(11 "B.Adhes" user "B.Adhesive")
		(13 "F.Paste" user "Package Geometry/Pastemask Top")
		(15 "B.Paste" user "Package Geometry/Pastemask Bottom")
		(5 "F.SilkS" user "Ref Des/Silkscreen Top")
		(7 "B.SilkS" user "Ref Des/Silkscreen Bottom")
		(1 "F.Mask" user "Board Geometry/Soldermask Top")
		(3 "B.Mask" user "Board Geometry/Soldermask Bottom")
		(17 "Dwgs.User" user "User.Drawings")
		(19 "Cmts.User" user "User.Comments")
		(21 "Eco1.User" user "User.Eco1")
		(23 "Eco2.User" user "User.Eco2")
		(25 "Edge.Cuts" user "Board Geometry/Outline")
		(27 "Margin" user)
		(31 "F.CrtYd" user "Package Geometry/Place Bound Top")
		(29 "B.CrtYd" user "Package Geometry/Place Bound Bottom")
		(35 "F.Fab" user "Ref Des/Assembly Top")
		(33 "B.Fab" user "Ref Des/Assembly Bottom")
	)
	(footprint ""
		(layer "F.Cu")
		(at 212.993732 -117.748812 180)
		(property "Reference" "R133"
			(at 0 0 180)
			(layer "F.SilkS")
			(hide yes)
			(effects
				(font
					(size 1.27 1.27)
				)
			)
		)
		(property "Value" ""
			(at 0 0 180)
			(layer "F.Fab")
			(effects
				(font
					(size 1.27 1.27)
				)
			)
		)
		(duplicate_pad_numbers_are_jumpers no)
		(fp_line
			(start 0.7874 0.4064)
			(end -0.7874 0.4064)
			(stroke
				(width 0.1524)
				(type default)
			)
			(layer "F.SilkS")
		)
		(fp_line
			(start 0.7874 -0.4064)
			(end 0.7874 0.4064)
			(stroke
				(width 0.1524)
				(type default)
			)
			(layer "F.SilkS")
		)
		(fp_line
			(start -0.7874 0.4064)
			(end -0.7874 -0.4064)
			(stroke
				(width 0.1524)
				(type default)
			)
			(layer "F.SilkS")
		)
		(fp_line
			(start -0.7874 -0.4064)
			(end 0.7874 -0.4064)
			(stroke
				(width 0.1524)
				(type default)
			)
			(layer "F.SilkS")
		)
		(fp_line
			(start 0.67945 0.3048)
			(end 0.120396 0.3048)
			(stroke
				(width 0.1)
				(type default)
			)
			(layer "F.Fab")
		)
		(fp_line
			(start 0.67945 -0.3048)
			(end 0.67945 0.3048)
			(stroke
				(width 0.1)
				(type default)
			)
			(layer "F.Fab")
		)
		(fp_line
			(start 0.12065 -0.2794)
			(end 0.12065 -0.3048)
			(stroke
				(width 0.1)
				(type default)
			)
			(layer "F.Fab")
		)
		(fp_line
			(start 0.12065 -0.3048)
			(end 0.67945 -0.3048)
			(stroke
				(width 0.1)
				(type default)
			)
			(layer "F.Fab")
		)
		(fp_line
			(start 0.120396 0.3048)
			(end 0.120396 0.2794)
			(stroke
				(width 0.1)
				(type default)
			)
			(layer "F.Fab")
		)
		(fp_line
			(start 0.120396 0.2794)
			(end -0.12065 0.2794)
			(stroke
				(width 0.1)
				(type default)
			)
			(layer "F.Fab")
		)
		(fp_line
			(start -0.12065 0.3048)
			(end -0.67945 0.3048)
			(stroke
				(width 0.1)
				(type default)
			)
			(layer "F.Fab")
		)
		(fp_line
			(start -0.12065 0.2794)
			(end -0.12065 0.3048)
			(stroke
				(width 0.1)
				(type default)
			)
			(layer "F.Fab")
		)
		(fp_line
			(start -0.12065 -0.2794)
			(end 0.12065 -0.2794)
			(stroke
				(width 0.1)
				(type default)
			)
			(layer "F.Fab")
		)
		(fp_line
			(start -0.12065 -0.305054)
			(end -0.12065 -0.2794)
			(stroke
				(width 0.1)
				(type default)
			)
			(layer "F.Fab")
		)
		(fp_line
			(start -0.67945 0.3048)
			(end -0.67945 -0.305054)
			(stroke
				(width 0.1)
				(type default)
			)
			(layer "F.Fab")
		)
		(fp_line
			(start -0.67945 -0.305054)
			(end -0.12065 -0.305054)
			(stroke
				(width 0.1)
				(type default)
			)
			(layer "F.Fab")
		)
		(pad "1" smd circle
			(at -0.40005 0 180)
			(size 0 0)
			(layers "F.Cu" "F.Mask" "F.Paste")
			(net "FM_APML_MUX2_SEL")
		)
		(pad "2" smd circle
			(at 0.40005 0 180)
			(size 0 0)
			(layers "F.Cu" "F.Mask" "F.Paste")
			(net "FM_APML_MUX2_SEL_R")
		)
	)
	(footprint ""
		(layer "F.Cu")
		(at 438.827418 -332.63586 -90)
		(property "Reference" "PC801"
			(at -4.98094 -2.990596 90)
			(unlocked yes)
			(layer "F.SilkS")
			(effects
				(font
					(size 0.7874 0.5842)
					(thickness 0.1524)
				)
				(justify left)
			)
		)
		(property "Value" ""
			(at 0 0 270)
			(layer "F.Fab")
			(effects
				(font
					(size 1.27 1.27)
				)
			)
		)
		(duplicate_pad_numbers_are_jumpers no)
		(fp_line
			(start -1.988058 2.750058)
			(end 2.750058 2.750058)
			(stroke
				(width 0.1524)
				(type default)
			)
			(layer "F.SilkS")
		)
		(fp_line
			(start 2.750058 2.750058)
			(end 2.750058 0.9398)
			(stroke
				(width 0.1524)
				(type default)
			)
			(layer "F.SilkS")
		)
		(fp_line
			(start -2.750058 1.988058)
			(end -1.988058 2.750058)
			(stroke
				(width 0.1524)
				(type default)
			)
			(layer "F.SilkS")
		)
		(fp_line
			(start -2.750058 0.9398)
			(end -2.750058 1.988058)
			(stroke
				(width 0.1524)
				(type default)
			)
			(layer "F.SilkS")
		)
		(fp_line
			(start 2.750058 -0.9398)
			(end 2.750058 -2.750058)
			(stroke
				(width 0.1524)
				(type default)
			)
			(layer "F.SilkS")
		)
		(fp_line
			(start -2.750058 -1.988058)
			(end -2.750058 -0.9398)
			(stroke
				(width 0.1524)
				(type default)
			)
			(layer "F.SilkS")
		)
		(fp_line
			(start -1.988058 -2.750058)
			(end -2.750058 -1.988058)
			(stroke
				(width 0.1524)
				(type default)
			)
			(layer "F.SilkS")
		)
		(fp_line
			(start 2.750058 -2.750058)
			(end -1.988058 -2.750058)
			(stroke
				(width 0.1524)
				(type default)
			)
			(layer "F.SilkS")
		)
		(fp_line
			(start -2.750058 2.750058)
			(end 2.750058 2.750058)
			(stroke
				(width 0.1)
				(type default)
			)
			(layer "F.Fab")
		)
		(fp_line
			(start 2.750058 2.750058)
			(end 2.750058 -2.750058)
			(stroke
				(width 0.1)
				(type default)
			)
			(layer "F.Fab")
		)
		(fp_line
			(start -2.750058 -2.750058)
			(end -2.750058 2.750058)
			(stroke
				(width 0.1)
				(type default)
			)
			(layer "F.Fab")
		)
		(fp_line
			(start 2.750058 -2.750058)
			(end -2.750058 -2.750058)
			(stroke
				(width 0.1)
				(type default)
			)
			(layer "F.Fab")
		)
		(pad "1" smd rect
			(at -2.199894 0)
			(size 1.6002 3.0226)
			(layers "F.Cu" "F.Mask" "F.Paste")
			(net "PVDD11_S3_P0")
		)
		(pad "2" smd rect
			(at 2.199894 0)
			(size 1.6002 3.0226)
			(layers "F.Cu" "F.Mask" "F.Paste")
			(net "GND")
		)
	)
)
